FILE_TYPE = MULTI_PHYS_TABLE;
PART 'CONN8_C77962004'
{===============================================================================================================================================================================================}
:PACK_TYPE |  MATERIAL  |  PART_NUMBER     = EnvComp                  |  PART_NUMBER  |     JEDEC_TYPE       |          DESCRIPTION                    | CLASS |  COMPONENT_TYPE  |  HEIGHT    | LEAD_LENGTH  | SPEED_URL | Status |RPL| AML | Bus_Unit | Days ;
{===============================================================================================================================================================================================}
'CONNLF'   |  'CONN'    | 'C77962-004'(!)  = 'YES;YES;UNK;UNK;ok;CIP' | 'C77962-004'  | 'CONN8_C77962004'    | 'HEADER - 8PIN .100 PITCH'              |  'IO' | 'THMT'           | '0.343 IN' | '0.085'      | 'http://speed.intel.com:8081/speed/module/pdm/item/pdm_item_detail_direct.asp?item_cde=C77962-004&item_rev=01&url_param=unused' | 'Unqual' | 'NO' | '1' | 'SMO_BOARDS' | '28' 
'CONNLF'   |  'EMPTY'   | 'C77962-004'(!)  = 'YES;YES;UNK;UNK;ok;CIP' | 'C77962-004'  | 'CONN8_C77962004'    | 'HEADER - 8PIN .100 PITCH'              |  'IO' | 'THMT'           | '0.343 IN' | '0.085'      | 'http://speed.intel.com:8081/speed/module/pdm/item/pdm_item_detail_direct.asp?item_cde=C77962-004&item_rev=01&url_param=unused' | 'Unqual' | 'NO' | '1' | 'SMO_BOARDS' | '28' 
'PIP'      |  'CONN'    | 'C77962-004'(!)  = ''                       | 'C77962-004'  | 'CONN8_C77962004_PIP'| 'PIP PHYSICAL HEADER - 8PIN .100 PITCH' |  'IO' | 'THMT'           | '0.343 IN' | '0.085'      | 'http://speed.intel.com:8081/speed/module/pdm/item/pdm_item_detail_direct.asp?item_cde=C77962-004&item_rev=01&url_param=unused' | '' | '' | '' | '' | '' 
'PIP'      |  'EMPTY'   | 'C77962-004'(!)  = ''                       | 'C77962-004'  | 'CONN8_C77962004_PIP'| 'PIP PHYSICAL HEADER - 8PIN .100 PITCH' |  'IO' | 'THMT'           | '0.343 IN' | '0.085'      | 'http://speed.intel.com:8081/speed/module/pdm/item/pdm_item_detail_direct.asp?item_cde=C77962-004&item_rev=01&url_param=unused' | '' | '' | '' | '' | '' 
END_PART
END.
